FILE_TYPE=LIBRARY_PARTS;
primitive 'Q_CAP_DIFFBUS';
  pin
    '1':
      PIN_NUMBER='(1)';
      BIDIRECTIONAL='TRUE';
      INPUT_LOAD='(-0.01,0.01)';
      OUTPUT_LOAD='(1.0,-1.0)';
    '2':
      PIN_NUMBER='(2)';
      BIDIRECTIONAL='TRUE';
      INPUT_LOAD='(-0.01,0.01)';
      OUTPUT_LOAD='(1.0,-1.0)';
  end_pin;
  body
    PART_NAME='Q_CAP_DIFFBUS';
    BODY_NAME='Q_CAP_DIFFBUS';
    PHYS_DES_PREFIX='C';
    CLASS='DISCRETE';
  end_body;
end_primitive;

END.
